FILE_TYPE = CONNECTIVITY;
{Allegro Design Entry HDL 17.2-2016 S081 (4005846) 1/11/2022}
"PAGE_NUMBER" = 60;
0"NC";
1"GND\g";
2"GND\g";
%"UNIVERSAL_GND"
"1","(-1075,4675)","1","pure_quanta_power","I1";
;
CDS_LIB"pure_quanta_power"
HDL_POWER"GND";
"A"2;
%"UNIVERSAL_GND"
"1","(-1650,3225)","1","pure_quanta_power","I2";
;
CDS_LIB"pure_quanta_power"
HDL_POWER"GND";
"A"1;
%"GENOA_SP5"
"40","(-4525,3950)","1","pure_quanta","I3";
;
LOCATION"U26"
$SEC"40"
CDS_SEC"40"
PART_TYPE"SMLF"
MATERIAL"IO"
VALUE"SOCKET6096_13568-001"
PART_NUMBER"DGA^6000030"
CDS_LIB"pure_quanta"
CDS_LMAN_SYM_OUTLINE"-400,3350,400,-3350"
NEEDS_NO_SIZE"TRUE";
"VSS_V68"
$PN"V68"2;
"VSS_BV42"
$PN"BV42"2;
"VSS_CT52"
$PN"CT52"2;
"VSS_CM50"
$PN"CM50"2;
"VSS_K59"
$PN"K59"2;
"VSS_DA56"
$PN"DA56"2;
"VSS_CG42"
$PN"CG42"2;
"VSS_AE4"
$PN"AE4"2;
"VSS_AH33"
$PN"AH33"2;
"VSS_BW25"
$PN"BW25"2;
"VSS_CU58"
$PN"CU58"2;
"VSS_P25"
$PN"P25"2;
"VSS_P68"
$PN"P68"2;
"VSS_AN20"
$PN"AN20"2;
"VSS_CC22"
$PN"CC22"2;
"VSS_CF46"
$PN"CF46"2;
"VSS_V27"
$PN"V27"2;
"VSS_AA42"
$PN"AA42"2;
"VSS_AD31"
$PN"AD31"2;
"VSS_AJ13"
$PN"AJ13"2;
"VSS_AA72"
$PN"AA72"2;
"VSS_CK10"
$PN"CK10"2;
"VSS_CN54"
$PN"CN54"2;
"VSS_K23"
$PN"K23"2;
"VSS_AM37"
$PN"AM37"2;
"VSS_CB44"
$PN"CB44"2;
"VSS_CK31"
$PN"CK31"2;
"VSS_CY57"
$PN"CY57"2;
"VSS_DJ73"
$PN"DJ73"2;
"VSS_DJ68"
$PN"DJ68"2;
"VSS_DJ66"
$PN"DJ66"2;
"VSS_DJ63"
$PN"DJ63"2;
"VSS_DJ61"
$PN"DJ61"2;
"VSS_DJ59"
$PN"DJ59"2;
"VSS_DJ49"
$PN"DJ49"2;
"VSS_DJ43"
$PN"DJ43"2;
"VSS_DJ19"
$PN"DJ19"2;
"VSS_DJ15"
$PN"DJ15"2;
"VSS_DJ7"
$PN"DJ7"2;
"VSS_DH70"
$PN"DH70"2;
"VSS_DH68"
$PN"DH68"2;
"VSS_DH59"
$PN"DH59"2;
"VSS_DH55"
$PN"DH55"2;
"VSS_DH52"
$PN"DH52"2;
"VSS_DH49"
$PN"DH49"2;
"VSS_DH46"
$PN"DH46"2;
"VSS_DH43"
$PN"DH43"2;
"VSS_DH39"
$PN"DH39"2;
"VSS_DG75"
$PN"DG75"2;
"VSS_DG74"
$PN"DG74"2;
"VSS_DG70"
$PN"DG70"2;
"VSS_DG69"
$PN"DG69"2;
"VSS_DG68"
$PN"DG68"2;
"VSS_DG67"
$PN"DG67"2;
"VSS_DG66"
$PN"DG66"2;
"VSS_DG60"
$PN"DG60"2;
"VSS_DG59"
$PN"DG59"2;
"VSS_DG56"
$PN"DG56"2;
"VSS_DG55"
$PN"DG55"2;
"VSS_DG52"
$PN"DG52"2;
"VSS_DG49"
$PN"DG49"2;
"VSS_DG46"
$PN"DG46"2;
"VSS_DG27"
$PN"DG27"2;
"VSS_DG24"
$PN"DG24"2;
"VSS_DG21"
$PN"DG21"2;
"VSS_DG20"
$PN"DG20"2;
"VSS_DG18"
$PN"DG18"2;
"VSS_DG16"
$PN"DG16"2;
"VSS_DG15"
$PN"DG15"2;
"VSS_DG7"
$PN"DG7"2;
"VSS_DG6"
$PN"DG6"2;
"VSS_DG2"
$PN"DG2"2;
"VSS_DG1"
$PN"DG1"2;
"VSS_DF73"
$PN"DF73"2;
"VSS_DF72"
$PN"DF72"2;
"VSS_DF71"
$PN"DF71"2;
"VSS_DF65"
$PN"DF65"2;
"VSS_DF64"
$PN"DF64"2;
"VSS_DF63"
$PN"DF63"2;
"VSS_DF61"
$PN"DF61"2;
"VSS_DF59"
$PN"DF59"2;
"VSS_DF58"
$PN"DF58"2;
"VSS_DF57"
$PN"DF57"2;
"VSS_DF56"
$PN"DF56"2;
"VSS_DF52"
$PN"DF52"2;
"VSS_DF51"
$PN"DF51"2;
"VSS_DF50"
$PN"DF50"2;
"VSS_DF49"
$PN"DF49"2;
"VSS_DF48"
$PN"DF48"2;
"VSS_DF47"
$PN"DF47"2;
"VSS_DF46"
$PN"DF46"2;
"VSS_DF45"
$PN"DF45"2;
"VSS_DF44"
$PN"DF44"2;
"VSS_DF42"
$PN"DF42"2;
"VSS_DF39"
$PN"DF39"2;
"VSS_DF37"
$PN"DF37"2;
"VSS_DF35"
$PN"DF35"2;
"VSS_DF32"
$PN"DF32"2;
"VSS_DF29"
$PN"DF29"2;
"VSS_DF26"
$PN"DF26"2;
"VSS_DF23"
$PN"DF23"2;
"VSS_DF22"
$PN"DF22"2;
"VSS_DF20"
$PN"DF20"2;
"VSS_DF13"
$PN"DF13"1;
"VSS_DF12"
$PN"DF12"1;
"VSS_DF11"
$PN"DF11"1;
"VSS_DF10"
$PN"DF10"1;
"VSS_DF8"
$PN"DF8"1;
"VSS_DF6"
$PN"DF6"1;
"VSS_DF5"
$PN"DF5"1;
"VSS_DE68"
$PN"DE68"1;
"VSS_DE63"
$PN"DE63"1;
"VSS_DE61"
$PN"DE61"1;
"VSS_DE56"
$PN"DE56"1;
"VSS_DE33"
$PN"DE33"1;
"VSS_DE29"
$PN"DE29"1;
"VSS_DE26"
$PN"DE26"1;
"VSS_DE8"
$PN"DE8"1;
"VSS_DE6"
$PN"DE6"1;
"VSS_DE1"
$PN"DE1"1;
"VSS_DD73"
$PN"DD73"1;
"VSS_DD71"
$PN"DD71"1;
"VSS_DD68"
$PN"DD68"1;
"VSS_DD66"
$PN"DD66"1;
"VSS_DD53"
$PN"DD53"1;
"VSS_DD52"
$PN"DD52"1;
"VSS_DD50"
$PN"DD50"1;
"VSS_DD49"
$PN"DD49"1;
"VSS_DD47"
$PN"DD47"1;
"VSS_DD46"
$PN"DD46"1;
"VSS_DD44"
$PN"DD44"1;
"VSS_DD37"
$PN"DD37"1;
"VSS_DD36"
$PN"DD36"1;
"VSS_DD35"
$PN"DD35"1;
"VSS_DD33"
$PN"DD33"1;
"VSS_DD32"
$PN"DD32"1;
"VSS_DD30"
$PN"DD30"1;
"VSS_DD29"
$PN"DD29"1;
"VSS_DD19"
$PN"DD19"1;
"VSS_DD17"
$PN"DD17"1;
"VSS_DD15"
$PN"DD15"1;
"VSS_DD12"
$PN"DD12"1;
"VSS_DD10"
$PN"DD10"1;
"VSS_DD8"
$PN"DD8"1;
"VSS_DD5"
$PN"DD5"1;
"VSS_DC68"
$PN"DC68"1;
"VSS_DC65"
$PN"DC65"1;
"VSS_DC63"
$PN"DC63"1;
"VSS_DC61"
$PN"DC61"1;
"VSS_DC58"
$PN"DC58"1;
"VSS_DC56"
$PN"DC56"1;
"VSS_DC54"
$PN"DC54"1;
"VSS_DC42"
$PN"DC42"1;
"VSS_DC34"
$PN"DC34"1;
"VSS_DC31"
$PN"DC31"1;
"VSS_DC28"
$PN"DC28"1;
"VSS_DC25"
$PN"DC25"1;
"VSS_DC22"
$PN"DC22"1;
"VSS_DC20"
$PN"DC20"1;
"VSS_DC18"
$PN"DC18"1;
"VSS_DC11"
$PN"DC11"1;
"VSS_DC8"
$PN"DC8"1;
"VSS_DC6"
$PN"DC6"1;
"VSS_DC4"
$PN"DC4"1;
"VSS_DC1"
$PN"DC1"1;
"VSS_DB73"
$PN"DB73"1;
"VSS_DB68"
$PN"DB68"1;
"VSS_DB66"
$PN"DB66"1;
"VSS_DB61"
$PN"DB61"1;
"VSS_DB45"
$PN"DB45"1;
"VSS_DB42"
$PN"DB42"1;
"VSS_DB39"
$PN"DB39"1;
"VSS_DB37"
$PN"DB37"1;
"VSS_DB34"
$PN"DB34"1;
"VSS_DB31"
$PN"DB31"1;
"VSS_DB28"
$PN"DB28"1;
"VSS_DB10"
$PN"DB10"1;
"VSS_DB8"
$PN"DB8"1;
"VSS_DB3"
$PN"DB3"1;
"VSS_DA75"
$PN"DA75"1;
"VSS_DA72"
$PN"DA72"1;
"VSS_DH66"
$PN"DH66"2;
"VSS_DH64"
$PN"DH64"2;
"VSS_DH63"
$PN"DH63"2;
"VSS_DH61"
$PN"DH61"2;
"VSS_DH37"
$PN"DH37"2;
"VSS_DH18"
$PN"DH18"2;
"VSS_DH11"
$PN"DH11"2;
"VSS_DH5"
$PN"DH5"2;
"VSS_DG65"
$PN"DG65"2;
"VSS_DG63"
$PN"DG63"2;
"VSS_DG62"
$PN"DG62"2;
"VSS_DG61"
$PN"DG61"2;
"VSS_DG43"
$PN"DG43"2;
"VSS_DG41"
$PN"DG41"2;
"VSS_DG33"
$PN"DG33"2;
"VSS_DG30"
$PN"DG30"2;
"VSS_DG14"
$PN"DG14"2;
"VSS_DG13"
$PN"DG13"2;
"VSS_DG9"
$PN"DG9"2;
"VSS_DG8"
$PN"DG8"2;
"VSS_DF70"
$PN"DF70"2;
"VSS_DF68"
$PN"DF68"2;
"VSS_DF66"
$PN"DF66"2;
"VSS_DF54"
$PN"DF54"2;
"VSS_DF53"
$PN"DF53"2;
"VSS_DF43"
$PN"DF43"2;
"VSS_DF19"
$PN"DF19"1;
"VSS_DF18"
$PN"DF18"1;
"VSS_DF17"
$PN"DF17"1;
"VSS_DF15"
$PN"DF15"1;
"VSS_DF4"
$PN"DF4"1;
"VSS_DF3"
$PN"DF3"1;
"VSS_DE75"
$PN"DE75"1;
"VSS_DE70"
$PN"DE70"1;
"VSS_DE23"
$PN"DE23"1;
"VSS_DE20"
$PN"DE20"1;
"VSS_DE15"
$PN"DE15"1;
"VSS_DE13"
$PN"DE13"1;
"VSS_DD64"
$PN"DD64"1;
"VSS_DD61"
$PN"DD61"1;
"VSS_DD59"
$PN"DD59"1;
"VSS_DD57"
$PN"DD57"1;
"VSS_DD43"
$PN"DD43"1;
"VSS_DD41"
$PN"DD41"1;
"VSS_DD40"
$PN"DD40"1;
"VSS_DD39"
$PN"DD39"1;
"VSS_DD27"
$PN"DD27"1;
"VSS_DD26"
$PN"DD26"1;
"VSS_DD24"
$PN"DD24"1;
"VSS_DD23"
$PN"DD23"1;
"VSS_DD3"
$PN"DD3"1;
"VSS_DC75"
$PN"DC75"1;
"VSS_DC72"
$PN"DC72"1;
"VSS_DC70"
$PN"DC70"1;
"VSS_DC51"
$PN"DC51"1;
"VSS_DC48"
$PN"DC48"1;
"VSS_DC45"
$PN"DC45"1;
"VSS_DC15"
$PN"DC15"1;
"VSS_DC13"
$PN"DC13"1;
"VSS_DB59"
$PN"DB59"1;
"VSS_DB54"
$PN"DB54"1;
"VSS_DB51"
$PN"DB51"1;
"VSS_DB48"
$PN"DB48"1;
"VSS_DB25"
$PN"DB25"1;
"VSS_DB22"
$PN"DB22"1;
"VSS_DB17"
$PN"DB17"1;
"VSS_DB15"
$PN"DB15"1;
END.
